(kicad_pcb
	(version 20260206)
	(generator "pcbnew")
	(generator_version "10.0")
	(general
		(thickness 1.6)
		(legacy_teardrops no)
	)
	(paper "A4")
	(title_block
		(title "Wiwynn_Tioga_Pass_MB.brd")
		(comment 1 "Tioga Pass / footprint 636 of 4770 (EU7F1), pads 1-43 of 43")
	)
	(layers
		(0 "F.Cu" signal "TOP")
		(4 "In1.Cu" signal "L2GND")
		(6 "In2.Cu" signal "L3")
		(8 "In3.Cu" signal "L4GND")
		(10 "In4.Cu" signal "L5")
		(12 "In5.Cu" signal "L6GND")
		(14 "In6.Cu" signal "L7VCC")
		(16 "In7.Cu" signal "L8VCC")
		(18 "In8.Cu" signal "L9GND")
		(20 "In9.Cu" signal "L10")
		(22 "In10.Cu" signal "L11GND")
		(24 "In11.Cu" signal "L12")
		(26 "In12.Cu" signal "L13GND")
		(2 "B.Cu" signal "BOTTOM")
		(9 "F.Adhes" user "F.Adhesive")
		(11 "B.Adhes" user "B.Adhesive")
		(13 "F.Paste" user "Package Geometry/Pastemask Top")
		(15 "B.Paste" user "Package Geometry/Pastemask Bottom")
		(5 "F.SilkS" user "Ref Des/Silkscreen Top")
		(7 "B.SilkS" user "Ref Des/Silkscreen Bottom")
		(1 "F.Mask" user "Board Geometry/Soldermask Top")
		(3 "B.Mask" user "Board Geometry/Soldermask Bottom")
		(17 "Dwgs.User" user "User.Drawings")
		(19 "Cmts.User" user "User.Comments")
		(21 "Eco1.User" user "User.Eco1")
		(23 "Eco2.User" user "User.Eco2")
		(25 "Edge.Cuts" user "Board Geometry/Outline")
		(27 "Margin" user)
		(31 "F.CrtYd" user "Package Geometry/Place Bound Top")
		(29 "B.CrtYd" user "Package Geometry/Place Bound Bottom")
		(35 "F.Fab" user "Ref Des/Assembly Top")
		(33 "B.Fab" user "Ref Des/Assembly Bottom")
	)
	(footprint ""
		(layer "F.Cu")
		(at 345.3638 -28.5623 90)
		(property "Reference" "EU7F1"
			(at 5.27939 -1.76022 0)
			(unlocked yes)
			(layer "F.SilkS")
			(effects
				(font
					(size 0.7874 0.5842)
					(thickness 0.1524)
				)
				(justify left)
			)
		)
		(property "Value" ""
			(at 0 0 90)
			(layer "F.Fab")
			(effects
				(font
					(size 1.27 1.27)
				)
			)
		)
		(duplicate_pad_numbers_are_jumpers no)
		(pad "1" smd custom
			(at -2.8321 -2.249932 90)
			(size 0.06985 0.06985)
			(layers "F.Cu" "F.Mask" "F.Paste")
			(net "VR_PVPP_ABC_SS")
			(options
				(clearance outline)
				(anchor circle)
			)
			(primitives
				(gr_poly
					(pts
						(arc
							(start 0.2413 -0.1397)
							(mid 0.381 0)
							(end 0.2413 0.1397)
						)
						(xy -0.381 0.1397) (xy -0.381 -0.1397)
					)
					(width 0)
					(fill yes)
				)
			)
		)
		(pad "2" smd custom
			(at -2.8321 -1.75006 90)
			(size 0.06985 0.06985)
			(layers "F.Cu" "F.Mask" "F.Paste")
			(net "VR_FB_PVPP_ABC")
			(options
				(clearance outline)
				(anchor circle)
			)
			(primitives
				(gr_poly
					(pts
						(arc
							(start 0.2413 -0.1397)
							(mid 0.381 0)
							(end 0.2413 0.1397)
						)
						(xy -0.381 0.1397) (xy -0.381 -0.1397)
					)
					(width 0)
					(fill yes)
				)
			)
		)
		(pad "3" smd custom
			(at -2.8321 -1.249934 90)
			(size 0.06985 0.06985)
			(layers "F.Cu" "F.Mask" "F.Paste")
			(net "VR_COMP_PVPP_ABC_3")
			(options
				(clearance outline)
				(anchor circle)
			)
			(primitives
				(gr_poly
					(pts
						(arc
							(start 0.2413 -0.1397)
							(mid 0.381 0)
							(end 0.2413 0.1397)
						)
						(xy -0.381 0.1397) (xy -0.381 -0.1397)
					)
					(width 0)
					(fill yes)
				)
			)
		)
		(pad "4" smd custom
			(at -2.8321 -0.750062 90)
			(size 0.06985 0.06985)
			(layers "F.Cu" "F.Mask" "F.Paste")
			(net "VR_PVPP_ABC_ISET")
			(options
				(clearance outline)
				(anchor circle)
			)
			(primitives
				(gr_poly
					(pts
						(arc
							(start 0.2413 -0.1397)
							(mid 0.381 0)
							(end 0.2413 0.1397)
						)
						(xy -0.381 0.1397) (xy -0.381 -0.1397)
					)
					(width 0)
					(fill yes)
				)
			)
		)
		(pad "5" smd custom
			(at -2.8321 -0.249936 90)
			(size 0.06985 0.06985)
			(layers "F.Cu" "F.Mask" "F.Paste")
			(net "AGND_PVPP_ABC")
			(options
				(clearance outline)
				(anchor circle)
			)
			(primitives
				(gr_poly
					(pts
						(arc
							(start 0.2413 -0.1397)
							(mid 0.381 0)
							(end 0.2413 0.1397)
						)
						(xy -0.381 0.1397) (xy -0.381 -0.1397)
					)
					(width 0)
					(fill yes)
				)
			)
		)
		(pad "6" smd custom
			(at -2.8321 0.249936 90)
			(size 0.06985 0.06985)
			(layers "F.Cu" "F.Mask" "F.Paste")
			(net "AGND_PVPP_ABC")
			(options
				(clearance outline)
				(anchor circle)
			)
			(primitives
				(gr_poly
					(pts
						(arc
							(start 0.2413 -0.1397)
							(mid 0.381 0)
							(end 0.2413 0.1397)
						)
						(xy -0.381 0.1397) (xy -0.381 -0.1397)
					)
					(width 0)
					(fill yes)
				)
			)
		)
		(pad "7" smd custom
			(at -2.8321 0.750062 90)
			(size 0.06985 0.06985)
			(layers "F.Cu" "F.Mask" "F.Paste")
			(net "PWRGD_PVPP_ABC_R")
			(options
				(clearance outline)
				(anchor circle)
			)
			(primitives
				(gr_poly
					(pts
						(arc
							(start 0.2413 -0.1397)
							(mid 0.381 0)
							(end 0.2413 0.1397)
						)
						(xy -0.381 0.1397) (xy -0.381 -0.1397)
					)
					(width 0)
					(fill yes)
				)
			)
		)
		(pad "8" smd custom
			(at -2.8321 1.249934 90)
			(size 0.06985 0.06985)
			(layers "F.Cu" "F.Mask" "F.Paste")
			(net "VR_FET_SW_P12V_STBY_PVPP_ABC")
			(options
				(clearance outline)
				(anchor circle)
			)
			(primitives
				(gr_poly
					(pts
						(arc
							(start 0.2413 -0.1397)
							(mid 0.381 0)
							(end 0.2413 0.1397)
						)
						(xy -0.381 0.1397) (xy -0.381 -0.1397)
					)
					(width 0)
					(fill yes)
				)
			)
		)
		(pad "9" smd custom
			(at -2.8321 1.75006 90)
			(size 0.06985 0.06985)
			(layers "F.Cu" "F.Mask" "F.Paste")
			(net "VR_FET_SW_P12V_STBY_PVPP_ABC")
			(options
				(clearance outline)
				(anchor circle)
			)
			(primitives
				(gr_poly
					(pts
						(arc
							(start 0.2413 -0.1397)
							(mid 0.381 0)
							(end 0.2413 0.1397)
						)
						(xy -0.381 0.1397) (xy -0.381 -0.1397)
					)
					(width 0)
					(fill yes)
				)
			)
		)
		(pad "10" smd custom
			(at -2.8321 2.249932 90)
			(size 0.06985 0.06985)
			(layers "F.Cu" "F.Mask" "F.Paste")
			(net "VR_FET_SW_P12V_STBY_PVPP_ABC")
			(options
				(clearance outline)
				(anchor circle)
			)
			(primitives
				(gr_poly
					(pts
						(arc
							(start 0.2413 -0.1397)
							(mid 0.381 0)
							(end 0.2413 0.1397)
						)
						(xy -0.381 0.1397) (xy -0.381 -0.1397)
					)
					(width 0)
					(fill yes)
				)
			)
		)
		(pad "11" smd custom
			(at -2.249932 2.8321 90)
			(size 0.06985 0.06985)
			(layers "F.Cu" "F.Mask" "F.Paste")
			(net "VR_FET_SW_P12V_STBY_PVPP_ABC")
			(options
				(clearance outline)
				(anchor circle)
			)
			(primitives
				(gr_poly
					(pts
						(arc
							(start -0.1397 -0.2413)
							(mid 0 -0.381)
							(end 0.1397 -0.2413)
						)
						(xy 0.1397 0.381) (xy -0.1397 0.381)
					)
					(width 0)
					(fill yes)
				)
			)
		)
		(pad "12" smd custom
			(at -1.75006 2.8321 90)
			(size 0.06985 0.06985)
			(layers "F.Cu" "F.Mask" "F.Paste")
			(net "VR_FET_SW_P12V_STBY_PVPP_ABC")
			(options
				(clearance outline)
				(anchor circle)
			)
			(primitives
				(gr_poly
					(pts
						(arc
							(start -0.1397 -0.2413)
							(mid 0 -0.381)
							(end 0.1397 -0.2413)
						)
						(xy 0.1397 0.381) (xy -0.1397 0.381)
					)
					(width 0)
					(fill yes)
				)
			)
		)
		(pad "13" smd custom
			(at -1.249934 2.8321 90)
			(size 0.06985 0.06985)
			(layers "F.Cu" "F.Mask" "F.Paste")
			(net "VR_FET_SW_P12V_STBY_PVPP_ABC")
			(options
				(clearance outline)
				(anchor circle)
			)
			(primitives
				(gr_poly
					(pts
						(arc
							(start -0.1397 -0.2413)
							(mid 0 -0.381)
							(end 0.1397 -0.2413)
						)
						(xy 0.1397 0.381) (xy -0.1397 0.381)
					)
					(width 0)
					(fill yes)
				)
			)
		)
		(pad "14" smd custom
			(at -0.750062 2.8321 90)
			(size 0.06985 0.06985)
			(layers "F.Cu" "F.Mask" "F.Paste")
			(net "VR_FET_SW_P12V_STBY_PVPP_ABC")
			(options
				(clearance outline)
				(anchor circle)
			)
			(primitives
				(gr_poly
					(pts
						(arc
							(start -0.1397 -0.2413)
							(mid 0 -0.381)
							(end 0.1397 -0.2413)
						)
						(xy 0.1397 0.381) (xy -0.1397 0.381)
					)
					(width 0)
					(fill yes)
				)
			)
		)
		(pad "15" smd custom
			(at -0.249936 2.8321 90)
			(size 0.06985 0.06985)
			(layers "F.Cu" "F.Mask" "F.Paste")
			(net "VR_PVPP_ABC_PHASE")
			(options
				(clearance outline)
				(anchor circle)
			)
			(primitives
				(gr_poly
					(pts
						(arc
							(start -0.1397 -0.2413)
							(mid 0 -0.381)
							(end 0.1397 -0.2413)
						)
						(xy 0.1397 0.381) (xy -0.1397 0.381)
					)
					(width 0)
					(fill yes)
				)
			)
		)
		(pad "16" smd custom
			(at 0.249936 2.8321 90)
			(size 0.06985 0.06985)
			(layers "F.Cu" "F.Mask" "F.Paste")
			(net "GND")
			(options
				(clearance outline)
				(anchor circle)
			)
			(primitives
				(gr_poly
					(pts
						(arc
							(start -0.1397 -0.2413)
							(mid 0 -0.381)
							(end 0.1397 -0.2413)
						)
						(xy 0.1397 0.381) (xy -0.1397 0.381)
					)
					(width 0)
					(fill yes)
				)
			)
		)
		(pad "17" smd custom
			(at 0.750062 2.8321 90)
			(size 0.06985 0.06985)
			(layers "F.Cu" "F.Mask" "F.Paste")
			(net "GND")
			(options
				(clearance outline)
				(anchor circle)
			)
			(primitives
				(gr_poly
					(pts
						(arc
							(start -0.1397 -0.2413)
							(mid 0 -0.381)
							(end 0.1397 -0.2413)
						)
						(xy 0.1397 0.381) (xy -0.1397 0.381)
					)
					(width 0)
					(fill yes)
				)
			)
		)
		(pad "18" smd custom
			(at 1.249934 2.8321 90)
			(size 0.06985 0.06985)
			(layers "F.Cu" "F.Mask" "F.Paste")
			(net "GND")
			(options
				(clearance outline)
				(anchor circle)
			)
			(primitives
				(gr_poly
					(pts
						(arc
							(start -0.1397 -0.2413)
							(mid 0 -0.381)
							(end 0.1397 -0.2413)
						)
						(xy 0.1397 0.381) (xy -0.1397 0.381)
					)
					(width 0)
					(fill yes)
				)
			)
		)
		(pad "19" smd custom
			(at 1.75006 2.8321 90)
			(size 0.06985 0.06985)
			(layers "F.Cu" "F.Mask" "F.Paste")
			(net "GND")
			(options
				(clearance outline)
				(anchor circle)
			)
			(primitives
				(gr_poly
					(pts
						(arc
							(start -0.1397 -0.2413)
							(mid 0 -0.381)
							(end 0.1397 -0.2413)
						)
						(xy 0.1397 0.381) (xy -0.1397 0.381)
					)
					(width 0)
					(fill yes)
				)
			)
		)
		(pad "20" smd custom
			(at 2.249932 2.8321 90)
			(size 0.06985 0.06985)
			(layers "F.Cu" "F.Mask" "F.Paste")
			(net "GND")
			(options
				(clearance outline)
				(anchor circle)
			)
			(primitives
				(gr_poly
					(pts
						(arc
							(start -0.1397 -0.2413)
							(mid 0 -0.381)
							(end 0.1397 -0.2413)
						)
						(xy 0.1397 0.381) (xy -0.1397 0.381)
					)
					(width 0)
					(fill yes)
				)
			)
		)
		(pad "21" smd custom
			(at 2.8321 2.249932 90)
			(size 0.06985 0.06985)
			(layers "F.Cu" "F.Mask" "F.Paste")
			(net "GND")
			(options
				(clearance outline)
				(anchor circle)
			)
			(primitives
				(gr_poly
					(pts
						(arc
							(start -0.2413 0.1397)
							(mid -0.381 0)
							(end -0.2413 -0.1397)
						)
						(xy 0.381 -0.1397) (xy 0.381 0.1397)
					)
					(width 0)
					(fill yes)
				)
			)
		)
		(pad "22" smd custom
			(at 2.8321 1.75006 90)
			(size 0.06985 0.06985)
			(layers "F.Cu" "F.Mask" "F.Paste")
			(net "GND")
			(options
				(clearance outline)
				(anchor circle)
			)
			(primitives
				(gr_poly
					(pts
						(arc
							(start -0.2413 0.1397)
							(mid -0.381 0)
							(end -0.2413 -0.1397)
						)
						(xy 0.381 -0.1397) (xy 0.381 0.1397)
					)
					(width 0)
					(fill yes)
				)
			)
		)
		(pad "23" smd custom
			(at 2.8321 1.249934 90)
			(size 0.06985 0.06985)
			(layers "F.Cu" "F.Mask" "F.Paste")
			(net "GND")
			(options
				(clearance outline)
				(anchor circle)
			)
			(primitives
				(gr_poly
					(pts
						(arc
							(start -0.2413 0.1397)
							(mid -0.381 0)
							(end -0.2413 -0.1397)
						)
						(xy 0.381 -0.1397) (xy 0.381 0.1397)
					)
					(width 0)
					(fill yes)
				)
			)
		)
		(pad "24" smd custom
			(at 2.8321 0.750062 90)
			(size 0.06985 0.06985)
			(layers "F.Cu" "F.Mask" "F.Paste")
			(net "GND")
			(options
				(clearance outline)
				(anchor circle)
			)
			(primitives
				(gr_poly
					(pts
						(arc
							(start -0.2413 0.1397)
							(mid -0.381 0)
							(end -0.2413 -0.1397)
						)
						(xy 0.381 -0.1397) (xy 0.381 0.1397)
					)
					(width 0)
					(fill yes)
				)
			)
		)
		(pad "25" smd custom
			(at 2.8321 0.249936 90)
			(size 0.06985 0.06985)
			(layers "F.Cu" "F.Mask" "F.Paste")
			(net "GND")
			(options
				(clearance outline)
				(anchor circle)
			)
			(primitives
				(gr_poly
					(pts
						(arc
							(start -0.2413 0.1397)
							(mid -0.381 0)
							(end -0.2413 -0.1397)
						)
						(xy 0.381 -0.1397) (xy 0.381 0.1397)
					)
					(width 0)
					(fill yes)
				)
			)
		)
		(pad "26" smd custom
			(at 2.8321 -0.249936 90)
			(size 0.06985 0.06985)
			(layers "F.Cu" "F.Mask" "F.Paste")
			(net "GND")
			(options
				(clearance outline)
				(anchor circle)
			)
			(primitives
				(gr_poly
					(pts
						(arc
							(start -0.2413 0.1397)
							(mid -0.381 0)
							(end -0.2413 -0.1397)
						)
						(xy 0.381 -0.1397) (xy 0.381 0.1397)
					)
					(width 0)
					(fill yes)
				)
			)
		)
		(pad "27" smd custom
			(at 2.8321 -0.750062 90)
			(size 0.06985 0.06985)
			(layers "F.Cu" "F.Mask" "F.Paste")
			(net "GND")
			(options
				(clearance outline)
				(anchor circle)
			)
			(primitives
				(gr_poly
					(pts
						(arc
							(start -0.2413 0.1397)
							(mid -0.381 0)
							(end -0.2413 -0.1397)
						)
						(xy 0.381 -0.1397) (xy 0.381 0.1397)
					)
					(width 0)
					(fill yes)
				)
			)
		)
		(pad "28" smd custom
			(at 2.8321 -1.249934 90)
			(size 0.06985 0.06985)
			(layers "F.Cu" "F.Mask" "F.Paste")
			(net "GND")
			(options
				(clearance outline)
				(anchor circle)
			)
			(primitives
				(gr_poly
					(pts
						(arc
							(start -0.2413 0.1397)
							(mid -0.381 0)
							(end -0.2413 -0.1397)
						)
						(xy 0.381 -0.1397) (xy 0.381 0.1397)
					)
					(width 0)
					(fill yes)
				)
			)
		)
		(pad "29" smd custom
			(at 2.8321 -1.75006 90)
			(size 0.06985 0.06985)
			(layers "F.Cu" "F.Mask" "F.Paste")
			(net "VR_PVPP_ABC_PHASE")
			(options
				(clearance outline)
				(anchor circle)
			)
			(primitives
				(gr_poly
					(pts
						(arc
							(start -0.2413 0.1397)
							(mid -0.381 0)
							(end -0.2413 -0.1397)
						)
						(xy 0.381 -0.1397) (xy 0.381 0.1397)
					)
					(width 0)
					(fill yes)
				)
			)
		)
		(pad "30" smd custom
			(at 2.8321 -2.249932 90)
			(size 0.06985 0.06985)
			(layers "F.Cu" "F.Mask" "F.Paste")
			(net "VR_PVPP_ABC_PHASE")
			(options
				(clearance outline)
				(anchor circle)
			)
			(primitives
				(gr_poly
					(pts
						(arc
							(start -0.2413 0.1397)
							(mid -0.381 0)
							(end -0.2413 -0.1397)
						)
						(xy 0.381 -0.1397) (xy 0.381 0.1397)
					)
					(width 0)
					(fill yes)
				)
			)
		)
		(pad "31" smd custom
			(at 2.249932 -2.8321 90)
			(size 0.06985 0.06985)
			(layers "F.Cu" "F.Mask" "F.Paste")
			(net "VR_PVPP_ABC_PHASE")
			(options
				(clearance outline)
				(anchor circle)
			)
			(primitives
				(gr_poly
					(pts
						(arc
							(start 0.1397 0.2413)
							(mid 0 0.381)
							(end -0.1397 0.2413)
						)
						(xy -0.1397 -0.381) (xy 0.1397 -0.381)
					)
					(width 0)
					(fill yes)
				)
			)
		)
		(pad "32" smd custom
			(at 1.75006 -2.8321 90)
			(size 0.06985 0.06985)
			(layers "F.Cu" "F.Mask" "F.Paste")
			(net "VR_PVPP_ABC_PHASE")
			(options
				(clearance outline)
				(anchor circle)
			)
			(primitives
				(gr_poly
					(pts
						(arc
							(start 0.1397 0.2413)
							(mid 0 0.381)
							(end -0.1397 0.2413)
						)
						(xy -0.1397 -0.381) (xy 0.1397 -0.381)
					)
					(width 0)
					(fill yes)
				)
			)
		)
		(pad "33" smd custom
			(at 1.249934 -2.8321 90)
			(size 0.06985 0.06985)
			(layers "F.Cu" "F.Mask" "F.Paste")
			(net "VR_PVPP_ABC_PHASE")
			(options
				(clearance outline)
				(anchor circle)
			)
			(primitives
				(gr_poly
					(pts
						(arc
							(start 0.1397 0.2413)
							(mid 0 0.381)
							(end -0.1397 0.2413)
						)
						(xy -0.1397 -0.381) (xy 0.1397 -0.381)
					)
					(width 0)
					(fill yes)
				)
			)
		)
		(pad "34" smd custom
			(at 0.750062 -2.8321 90)
			(size 0.06985 0.06985)
			(layers "F.Cu" "F.Mask" "F.Paste")
			(net "VR_PVPP_ABC_PHASE")
			(options
				(clearance outline)
				(anchor circle)
			)
			(primitives
				(gr_poly
					(pts
						(arc
							(start 0.1397 0.2413)
							(mid 0 0.381)
							(end -0.1397 0.2413)
						)
						(xy -0.1397 -0.381) (xy 0.1397 -0.381)
					)
					(width 0)
					(fill yes)
				)
			)
		)
		(pad "35" smd custom
			(at 0.249936 -2.8321 90)
			(size 0.06985 0.06985)
			(layers "F.Cu" "F.Mask" "F.Paste")
			(net "VR_PVPP_ABC_PHASE")
			(options
				(clearance outline)
				(anchor circle)
			)
			(primitives
				(gr_poly
					(pts
						(arc
							(start 0.1397 0.2413)
							(mid 0 0.381)
							(end -0.1397 0.2413)
						)
						(xy -0.1397 -0.381) (xy 0.1397 -0.381)
					)
					(width 0)
					(fill yes)
				)
			)
		)
		(pad "36" smd custom
			(at -0.249936 -2.8321 90)
			(size 0.06985 0.06985)
			(layers "F.Cu" "F.Mask" "F.Paste")
			(net "VR_PVPP_ABC_BOOT")
			(options
				(clearance outline)
				(anchor circle)
			)
			(primitives
				(gr_poly
					(pts
						(arc
							(start 0.1397 0.2413)
							(mid 0 0.381)
							(end -0.1397 0.2413)
						)
						(xy -0.1397 -0.381) (xy 0.1397 -0.381)
					)
					(width 0)
					(fill yes)
				)
			)
		)
		(pad "37" smd custom
			(at -0.750062 -2.8321 90)
			(size 0.06985 0.06985)
			(layers "F.Cu" "F.Mask" "F.Paste")
			(net "GND")
			(options
				(clearance outline)
				(anchor circle)
			)
			(primitives
				(gr_poly
					(pts
						(arc
							(start 0.1397 0.2413)
							(mid 0 0.381)
							(end -0.1397 0.2413)
						)
						(xy -0.1397 -0.381) (xy 0.1397 -0.381)
					)
					(width 0)
					(fill yes)
				)
			)
		)
		(pad "38" smd custom
			(at -1.249934 -2.8321 90)
			(size 0.06985 0.06985)
			(layers "F.Cu" "F.Mask" "F.Paste")
			(net "VR_VB_PVPP_ABC")
			(options
				(clearance outline)
				(anchor circle)
			)
			(primitives
				(gr_poly
					(pts
						(arc
							(start 0.1397 0.2413)
							(mid 0 0.381)
							(end -0.1397 0.2413)
						)
						(xy -0.1397 -0.381) (xy 0.1397 -0.381)
					)
					(width 0)
					(fill yes)
				)
			)
		)
		(pad "39" smd custom
			(at -1.75006 -2.8321 90)
			(size 0.06985 0.06985)
			(layers "F.Cu" "F.Mask" "F.Paste")
			(net "VR_FET_SW_P12V_STBY_PVPP_ABC")
			(options
				(clearance outline)
				(anchor circle)
			)
			(primitives
				(gr_poly
					(pts
						(arc
							(start 0.1397 0.2413)
							(mid 0 0.381)
							(end -0.1397 0.2413)
						)
						(xy -0.1397 -0.381) (xy 0.1397 -0.381)
					)
					(width 0)
					(fill yes)
				)
			)
		)
		(pad "40" smd custom
			(at -2.249932 -2.8321 90)
			(size 0.06985 0.06985)
			(layers "F.Cu" "F.Mask" "F.Paste")
			(net "FM_PVPP_PVDDQ_CPU0_EN_ABC")
			(options
				(clearance outline)
				(anchor circle)
			)
			(primitives
				(gr_poly
					(pts
						(arc
							(start 0.1397 0.2413)
							(mid 0 0.381)
							(end -0.1397 0.2413)
						)
						(xy -0.1397 -0.381) (xy 0.1397 -0.381)
					)
					(width 0)
					(fill yes)
				)
			)
		)
		(pad "41" smd rect
			(at -1.4478 -1.1938 90)
			(size 1.4986 2.0066)
			(layers "F.Cu" "F.Mask" "F.Paste")
			(net "GND")
		)
		(pad "42" smd rect
			(at -1.4478 1.1938 90)
			(size 1.4986 2.0066)
			(layers "F.Cu" "F.Mask" "F.Paste")
			(net "VR_FET_SW_P12V_STBY_PVPP_ABC")
		)
		(pad "43" smd rect
			(at 1.0033 0 90)
			(size 2.3876 4.3942)
			(layers "F.Cu" "F.Mask" "F.Paste")
			(net "VR_PVPP_ABC_PHASE")
		)
	)
)
